# S9S_MB_2U (Grand Teton) — schematic netlist excerpt (pin names and nets, part order shuffled) for the footprints in the layout excerpt that follows; sources: Cadence DE-HDL packaged netlist, KiCad conversion of 03242023_DA0F0TMBIJ0_F0T_Motherboard_J_brd_V01_OCP.brd

C756  Q_CAP_DIFFBUS  DIFF BUS_0.22UF 6.3V 20% X6S  pkg C0201  page 176 : \1\ = P5E_CPU1_PE2_TX_C_DN<8> ; \2\ = P5E_CPU1_PE2_TX_DN<8>
C1823  Q_CAP  0.1UF 25V 10% X7R  pkg 0402  page 161 : A = P3V3_AUX ; B = GND
R4763  Q_RES  10K 1% CHIP  pkg 0402LF  page 164 : A = P3V3_AUX ; B = HP_OCP_V3_2_EN

(kicad_pcb
	(version 20260206)
	(generator "pcbnew")
	(generator_version "10.0")
	(general
		(thickness 1.6)
		(legacy_teardrops no)
	)
	(paper "A4")
	(title_block
		(title "03242023_DA0F0TMBIJ0_F0T_Motherboard_J_brd_V01_OCP.brd")
		(comment 1 "Grand Teton / footprints 2051-2053 of 6105")
	)
	(layers
		(0 "F.Cu" signal "TOP")
		(4 "In1.Cu" signal "GND")
		(6 "In2.Cu" signal "IN1")
		(8 "In3.Cu" signal "GND1")
		(10 "In4.Cu" signal "IN2")
		(12 "In5.Cu" signal "GND2")
		(14 "In6.Cu" signal "IN3")
		(16 "In7.Cu" signal "GND3")
		(18 "In8.Cu" signal "VCC")
		(20 "In9.Cu" signal "VCC1")
		(22 "In10.Cu" signal "GND4")
		(24 "In11.Cu" signal "IN4")
		(26 "In12.Cu" signal "GND5")
		(28 "In13.Cu" signal "IN5")
		(30 "In14.Cu" signal "GND6")
		(32 "In15.Cu" signal "IN6")
		(34 "In16.Cu" signal "GND7")
		(2 "B.Cu" signal "BOTTOM")
		(9 "F.Adhes" user "F.Adhesive")
		(11 "B.Adhes" user "B.Adhesive")
		(13 "F.Paste" user "Package Geometry/Pastemask Top")
		(15 "B.Paste" user "Package Geometry/Pastemask Bottom")
		(5 "F.SilkS" user "Ref Des/Silkscreen Top")
		(7 "B.SilkS" user "Ref Des/Silkscreen Bottom")
		(1 "F.Mask" user "Board Geometry/Soldermask Top")
		(3 "B.Mask" user "Board Geometry/Soldermask Bottom")
		(17 "Dwgs.User" user "User.Drawings")
		(19 "Cmts.User" user "User.Comments")
		(21 "Eco1.User" user "User.Eco1")
		(23 "Eco2.User" user "User.Eco2")
		(25 "Edge.Cuts" user "Board Geometry/Outline")
		(27 "Margin" user)
		(31 "F.CrtYd" user "Package Geometry/Place Bound Top")
		(29 "B.CrtYd" user "Package Geometry/Place Bound Bottom")
		(35 "F.Fab" user "Ref Des/Assembly Top")
		(33 "B.Fab" user "Ref Des/Assembly Bottom")
	)
	(footprint ""
		(layer "F.Cu")
		(at 133.19252 -121.536968)
		(property "Reference" "R4763"
			(at 0 0 0)
			(layer "F.SilkS")
			(hide yes)
			(effects
				(font
					(size 1.27 1.27)
				)
			)
		)
		(property "Value" ""
			(at 0 0 0)
			(layer "F.Fab")
			(effects
				(font
					(size 1.27 1.27)
				)
			)
		)
		(duplicate_pad_numbers_are_jumpers no)
		(fp_line
			(start -0.7874 -0.4064)
			(end 0.7874 -0.4064)
			(stroke
				(width 0.1524)
				(type default)
			)
			(layer "F.SilkS")
		)
		(fp_line
			(start -0.7874 0.4064)
			(end -0.7874 -0.4064)
			(stroke
				(width 0.1524)
				(type default)
			)
			(layer "F.SilkS")
		)
		(fp_line
			(start 0.7874 -0.4064)
			(end 0.7874 0.4064)
			(stroke
				(width 0.1524)
				(type default)
			)
			(layer "F.SilkS")
		)
		(fp_line
			(start 0.7874 0.4064)
			(end -0.7874 0.4064)
			(stroke
				(width 0.1524)
				(type default)
			)
			(layer "F.SilkS")
		)
		(fp_line
			(start -0.67945 -0.305054)
			(end -0.12065 -0.305054)
			(stroke
				(width 0.1)
				(type default)
			)
			(layer "F.Fab")
		)
		(fp_line
			(start -0.67945 0.3048)
			(end -0.67945 -0.305054)
			(stroke
				(width 0.1)
				(type default)
			)
			(layer "F.Fab")
		)
		(fp_line
			(start -0.12065 -0.305054)
			(end -0.12065 -0.2794)
			(stroke
				(width 0.1)
				(type default)
			)
			(layer "F.Fab")
		)
		(fp_line
			(start -0.12065 -0.2794)
			(end 0.12065 -0.2794)
			(stroke
				(width 0.1)
				(type default)
			)
			(layer "F.Fab")
		)
		(fp_line
			(start -0.12065 0.2794)
			(end -0.12065 0.3048)
			(stroke
				(width 0.1)
				(type default)
			)
			(layer "F.Fab")
		)
		(fp_line
			(start -0.12065 0.3048)
			(end -0.67945 0.3048)
			(stroke
				(width 0.1)
				(type default)
			)
			(layer "F.Fab")
		)
		(fp_line
			(start 0.120396 0.2794)
			(end -0.12065 0.2794)
			(stroke
				(width 0.1)
				(type default)
			)
			(layer "F.Fab")
		)
		(fp_line
			(start 0.120396 0.3048)
			(end 0.120396 0.2794)
			(stroke
				(width 0.1)
				(type default)
			)
			(layer "F.Fab")
		)
		(fp_line
			(start 0.12065 -0.3048)
			(end 0.67945 -0.3048)
			(stroke
				(width 0.1)
				(type default)
			)
			(layer "F.Fab")
		)
		(fp_line
			(start 0.12065 -0.2794)
			(end 0.12065 -0.3048)
			(stroke
				(width 0.1)
				(type default)
			)
			(layer "F.Fab")
		)
		(fp_line
			(start 0.67945 -0.3048)
			(end 0.67945 0.3048)
			(stroke
				(width 0.1)
				(type default)
			)
			(layer "F.Fab")
		)
		(fp_line
			(start 0.67945 0.3048)
			(end 0.120396 0.3048)
			(stroke
				(width 0.1)
				(type default)
			)
			(layer "F.Fab")
		)
		(pad "1" smd circle
			(at -0.40005 0)
			(size 0 0)
			(layers "F.Cu" "F.Mask" "F.Paste")
			(net "P3V3_AUX")
		)
		(pad "2" smd circle
			(at 0.40005 0)
			(size 0 0)
			(layers "F.Cu" "F.Mask" "F.Paste")
			(net "HP_OCP_V3_2_EN")
		)
	)
	(footprint ""
		(layer "F.Cu")
		(at 111.21136 -31.437834 90)
		(property "Reference" "C1823"
			(at 0 0 90)
			(layer "F.SilkS")
			(hide yes)
			(effects
				(font
					(size 1.27 1.27)
				)
			)
		)
		(property "Value" ""
			(at 0 0 90)
			(layer "F.Fab")
			(effects
				(font
					(size 1.27 1.27)
				)
			)
		)
		(duplicate_pad_numbers_are_jumpers no)
		(fp_line
			(start 0.7874 -0.4064)
			(end 0.7874 0.4064)
			(stroke
				(width 0.1524)
				(type default)
			)
			(layer "F.SilkS")
		)
		(fp_line
			(start -0.7874 -0.4064)
			(end 0.7874 -0.4064)
			(stroke
				(width 0.1524)
				(type default)
			)
			(layer "F.SilkS")
		)
		(fp_line
			(start 0.7874 0.4064)
			(end -0.7874 0.4064)
			(stroke
				(width 0.1524)
				(type default)
			)
			(layer "F.SilkS")
		)
		(fp_line
			(start -0.7874 0.4064)
			(end -0.7874 -0.4064)
			(stroke
				(width 0.1524)
				(type default)
			)
			(layer "F.SilkS")
		)
		(fp_line
			(start -0.12065 -0.305054)
			(end -0.12065 -0.2794)
			(stroke
				(width 0.1)
				(type default)
			)
			(layer "F.Fab")
		)
		(fp_line
			(start -0.67945 -0.305054)
			(end -0.12065 -0.305054)
			(stroke
				(width 0.1)
				(type default)
			)
			(layer "F.Fab")
		)
		(fp_line
			(start 0.67945 -0.3048)
			(end 0.67945 0.3048)
			(stroke
				(width 0.1)
				(type default)
			)
			(layer "F.Fab")
		)
		(fp_line
			(start 0.12065 -0.3048)
			(end 0.67945 -0.3048)
			(stroke
				(width 0.1)
				(type default)
			)
			(layer "F.Fab")
		)
		(fp_line
			(start 0.12065 -0.2794)
			(end 0.12065 -0.3048)
			(stroke
				(width 0.1)
				(type default)
			)
			(layer "F.Fab")
		)
		(fp_line
			(start -0.12065 -0.2794)
			(end 0.12065 -0.2794)
			(stroke
				(width 0.1)
				(type default)
			)
			(layer "F.Fab")
		)
		(fp_line
			(start 0.120396 0.2794)
			(end -0.12065 0.2794)
			(stroke
				(width 0.1)
				(type default)
			)
			(layer "F.Fab")
		)
		(fp_line
			(start -0.12065 0.2794)
			(end -0.12065 0.3048)
			(stroke
				(width 0.1)
				(type default)
			)
			(layer "F.Fab")
		)
		(fp_line
			(start 0.67945 0.3048)
			(end 0.120396 0.3048)
			(stroke
				(width 0.1)
				(type default)
			)
			(layer "F.Fab")
		)
		(fp_line
			(start 0.120396 0.3048)
			(end 0.120396 0.2794)
			(stroke
				(width 0.1)
				(type default)
			)
			(layer "F.Fab")
		)
		(fp_line
			(start -0.12065 0.3048)
			(end -0.67945 0.3048)
			(stroke
				(width 0.1)
				(type default)
			)
			(layer "F.Fab")
		)
		(fp_line
			(start -0.67945 0.3048)
			(end -0.67945 -0.305054)
			(stroke
				(width 0.1)
				(type default)
			)
			(layer "F.Fab")
		)
		(pad "1" smd circle
			(at -0.40005 0 90)
			(size 0 0)
			(layers "F.Cu" "F.Mask" "F.Paste")
			(net "P3V3_AUX")
		)
		(pad "2" smd circle
			(at 0.40005 0 90)
			(size 0 0)
			(layers "F.Cu" "F.Mask" "F.Paste")
			(net "GND")
		)
	)
	(footprint ""
		(layer "F.Cu")
		(at 142.486634 -402.371052 -90)
		(property "Reference" "C756"
			(at 0 0 270)
			(layer "F.SilkS")
			(hide yes)
			(effects
				(font
					(size 1.27 1.27)
				)
			)
		)
		(property "Value" ""
			(at 0 0 270)
			(layer "F.Fab")
			(effects
				(font
					(size 1.27 1.27)
				)
			)
		)
		(duplicate_pad_numbers_are_jumpers no)
		(fp_line
			(start -0.299974 0.150114)
			(end -0.299974 -0.150114)
			(stroke
				(width 0.1)
				(type default)
			)
			(layer "F.Fab")
		)
		(fp_line
			(start 0.299974 0.150114)
			(end -0.299974 0.150114)
			(stroke
				(width 0.1)
				(type default)
			)
			(layer "F.Fab")
		)
		(fp_line
			(start -0.299974 -0.150114)
			(end 0.299974 -0.150114)
			(stroke
				(width 0.1)
				(type default)
			)
			(layer "F.Fab")
		)
		(fp_line
			(start 0.299974 -0.150114)
			(end 0.299974 0.150114)
			(stroke
				(width 0.1)
				(type default)
			)
			(layer "F.Fab")
		)
		(pad "1" smd rect
			(at -0.2667 0 270)
			(size 0.3048 0.381)
			(layers "F.Cu" "F.Mask" "F.Paste")
			(net "P5E_CPU1_PE2_TX_C_DN<8>")
		)
		(pad "2" smd rect
			(at 0.2667 0 270)
			(size 0.3048 0.381)
			(layers "F.Cu" "F.Mask" "F.Paste")
			(net "P5E_CPU1_PE2_TX_DN<8>")
		)
	)
)
